# BASEBOARD_FAB2 (Tioga Pass) — schematic netlist excerpt (pin names and nets, part order shuffled) for the footprints in the layout excerpt that follows; sources: Cadence DE-HDL packaged netlist, KiCad conversion of Wiwynn_Tioga_Pass_MB.brd

R25W165  RES  100.0 1% CHIP  pkg 0402  page 255 : A = P0V7_GTL2014_VREF_6 ; B = GND
R9P23  RES  100.0K 1% CHIP  pkg 0402  page 199 : A = P12V_STBY ; B = A_HSC_PWGIN
C25W76  CAP  12.0PF 50V 5% COG  pkg 0402LF  page 252 : A = V_IO_G_J ; B = GND

(kicad_pcb
	(version 20260206)
	(generator "pcbnew")
	(generator_version "10.0")
	(general
		(thickness 1.6)
		(legacy_teardrops no)
	)
	(paper "A4")
	(title_block
		(title "Wiwynn_Tioga_Pass_MB.brd")
		(comment 1 "Tioga Pass / footprints 3965-3967 of 4770")
	)
	(layers
		(0 "F.Cu" signal "TOP")
		(4 "In1.Cu" signal "L2GND")
		(6 "In2.Cu" signal "L3")
		(8 "In3.Cu" signal "L4GND")
		(10 "In4.Cu" signal "L5")
		(12 "In5.Cu" signal "L6GND")
		(14 "In6.Cu" signal "L7VCC")
		(16 "In7.Cu" signal "L8VCC")
		(18 "In8.Cu" signal "L9GND")
		(20 "In9.Cu" signal "L10")
		(22 "In10.Cu" signal "L11GND")
		(24 "In11.Cu" signal "L12")
		(26 "In12.Cu" signal "L13GND")
		(2 "B.Cu" signal "BOTTOM")
		(9 "F.Adhes" user "F.Adhesive")
		(11 "B.Adhes" user "B.Adhesive")
		(13 "F.Paste" user "Package Geometry/Pastemask Top")
		(15 "B.Paste" user "Package Geometry/Pastemask Bottom")
		(5 "F.SilkS" user "Ref Des/Silkscreen Top")
		(7 "B.SilkS" user "Ref Des/Silkscreen Bottom")
		(1 "F.Mask" user "Board Geometry/Soldermask Top")
		(3 "B.Mask" user "Board Geometry/Soldermask Bottom")
		(17 "Dwgs.User" user "User.Drawings")
		(19 "Cmts.User" user "User.Comments")
		(21 "Eco1.User" user "User.Eco1")
		(23 "Eco2.User" user "User.Eco2")
		(25 "Edge.Cuts" user "Board Geometry/Outline")
		(27 "Margin" user)
		(31 "F.CrtYd" user "Package Geometry/Place Bound Top")
		(29 "B.CrtYd" user "Package Geometry/Place Bound Bottom")
		(35 "F.Fab" user "Ref Des/Assembly Top")
		(33 "B.Fab" user "Ref Des/Assembly Bottom")
	)
	(footprint ""
		(layer "B.Cu")
		(at 420.624 -23.114 180)
		(property "Reference" "C25W76"
			(at 0.8382 -0.67818 180)
			(unlocked yes)
			(layer "B.SilkS")
			(effects
				(font
					(size 0.4064 0.254)
					(thickness 0.1524)
				)
				(justify left mirror)
			)
		)
		(property "Value" ""
			(at 0 0 0)
			(layer "B.Fab")
			(effects
				(font
					(size 1.27 1.27)
				)
				(justify mirror)
			)
		)
		(duplicate_pad_numbers_are_jumpers no)
		(fp_poly
			(pts
				(xy -0.3048 -0.1016) (xy -0.3048 0.9906) (xy 0.3048 0.9906) (xy 0.3048 -0.1016)
			)
			(stroke
				(width 0)
				(type default)
			)
			(fill no)
			(layer "B.CrtYd")
		)
		(fp_line
			(start 0.3048 0.9906)
			(end -0.3048 0.9906)
			(stroke
				(width 0.1)
				(type default)
			)
			(layer "B.Fab")
		)
		(fp_line
			(start 0.3048 -0.1016)
			(end 0.3048 0.9906)
			(stroke
				(width 0.1)
				(type default)
			)
			(layer "B.Fab")
		)
		(fp_line
			(start -0.3048 0.9906)
			(end -0.3048 -0.1016)
			(stroke
				(width 0.1)
				(type default)
			)
			(layer "B.Fab")
		)
		(fp_line
			(start -0.3048 -0.1016)
			(end 0.3048 -0.1016)
			(stroke
				(width 0.1)
				(type default)
			)
			(layer "B.Fab")
		)
		(pad "1" smd rect
			(at 0 0)
			(size 0.508 0.508)
			(layers "B.Cu" "B.Mask" "B.Paste")
			(net "V_IO_G_J")
		)
		(pad "2" smd rect
			(at 0 0.889)
			(size 0.508 0.508)
			(layers "B.Cu" "B.Mask" "B.Paste")
			(net "GND")
		)
		(zone
			(layer "B.Cu")
			(hatch none 0.5)
			(connect_pads
				(clearance 0)
			)
			(min_thickness 0.25)
			(keepout
				(tracks not_allowed)
				(vias allowed)
				(pads allowed)
				(copperpour not_allowed)
				(footprints allowed)
			)
			(placement
				(enabled no)
				(sheetname "")
			)
			(fill
				(thermal_gap 0.5)
				(thermal_bridge_width 0.5)
				(island_removal_mode 0)
			)
			(polygon
				(pts
					(xy 420.37 -23.749) (xy 420.878 -23.749) (xy 420.878 -23.368) (xy 420.37 -23.368)
				)
			)
		)
		(zone
			(layer "B.Cu")
			(hatch none 0.5)
			(connect_pads
				(clearance 0)
			)
			(min_thickness 0.25)
			(keepout
				(tracks allowed)
				(vias not_allowed)
				(pads allowed)
				(copperpour not_allowed)
				(footprints allowed)
			)
			(placement
				(enabled no)
				(sheetname "")
			)
			(fill
				(thermal_gap 0.5)
				(thermal_bridge_width 0.5)
				(island_removal_mode 0)
			)
			(polygon
				(pts
					(xy 420.37 -23.368) (xy 420.878 -23.368) (xy 420.878 -23.749) (xy 420.37 -23.749)
				)
			)
		)
	)
	(footprint ""
		(layer "B.Cu")
		(at 14.224 -76.1238)
		(property "Reference" "R9P23"
			(at 0 0 0)
			(layer "B.SilkS")
			(hide yes)
			(effects
				(font
					(size 1.27 1.27)
				)
				(justify mirror)
			)
		)
		(property "Value" ""
			(at 0 0 0)
			(layer "B.Fab")
			(effects
				(font
					(size 1.27 1.27)
				)
				(justify mirror)
			)
		)
		(duplicate_pad_numbers_are_jumpers no)
		(fp_poly
			(pts
				(xy 0.2794 -0.1016) (xy -0.2794 -0.1016) (xy -0.2794 0.9906) (xy 0.2794 0.9906)
			)
			(stroke
				(width 0)
				(type default)
			)
			(fill no)
			(layer "B.CrtYd")
		)
		(fp_line
			(start -0.2794 -0.1016)
			(end 0.2794 -0.1016)
			(stroke
				(width 0.1)
				(type default)
			)
			(layer "B.Fab")
		)
		(fp_line
			(start -0.2794 0.9906)
			(end -0.2794 -0.1016)
			(stroke
				(width 0.1)
				(type default)
			)
			(layer "B.Fab")
		)
		(fp_line
			(start 0.2794 -0.1016)
			(end 0.2794 0.9906)
			(stroke
				(width 0.1)
				(type default)
			)
			(layer "B.Fab")
		)
		(fp_line
			(start 0.2794 0.9906)
			(end -0.2794 0.9906)
			(stroke
				(width 0.1)
				(type default)
			)
			(layer "B.Fab")
		)
		(pad "1" smd rect
			(at 0 0 180)
			(size 0.508 0.508)
			(layers "B.Cu" "B.Mask" "B.Paste")
			(net "P12V_STBY")
		)
		(pad "2" smd rect
			(at 0 0.889 180)
			(size 0.508 0.508)
			(layers "B.Cu" "B.Mask" "B.Paste")
			(net "A_HSC_PWGIN")
		)
		(zone
			(layer "B.Cu")
			(hatch none 0.5)
			(connect_pads
				(clearance 0)
			)
			(min_thickness 0.25)
			(keepout
				(tracks allowed)
				(vias not_allowed)
				(pads allowed)
				(copperpour not_allowed)
				(footprints allowed)
			)
			(placement
				(enabled no)
				(sheetname "")
			)
			(fill
				(thermal_gap 0.5)
				(thermal_bridge_width 0.5)
				(island_removal_mode 0)
			)
			(polygon
				(pts
					(xy 14.478 -75.8698) (xy 13.97 -75.8698) (xy 13.97 -75.4888) (xy 14.478 -75.4888)
				)
			)
		)
		(zone
			(layer "B.Cu")
			(hatch none 0.5)
			(connect_pads
				(clearance 0)
			)
			(min_thickness 0.25)
			(keepout
				(tracks not_allowed)
				(vias allowed)
				(pads allowed)
				(copperpour not_allowed)
				(footprints allowed)
			)
			(placement
				(enabled no)
				(sheetname "")
			)
			(fill
				(thermal_gap 0.5)
				(thermal_bridge_width 0.5)
				(island_removal_mode 0)
			)
			(polygon
				(pts
					(xy 14.478 -75.4888) (xy 13.97 -75.4888) (xy 13.97 -75.8698) (xy 14.478 -75.8698)
				)
			)
		)
	)
	(footprint ""
		(layer "B.Cu")
		(at 450.2277 -149.3774 -90)
		(property "Reference" "R25W165"
			(at 0.8382 -0.67818 270)
			(unlocked yes)
			(layer "B.SilkS")
			(effects
				(font
					(size 0.4064 0.254)
					(thickness 0.1524)
				)
				(justify left mirror)
			)
		)
		(property "Value" ""
			(at 0 0 90)
			(layer "B.Fab")
			(effects
				(font
					(size 1.27 1.27)
				)
				(justify mirror)
			)
		)
		(duplicate_pad_numbers_are_jumpers no)
		(fp_poly
			(pts
				(xy 0.2794 -0.1016) (xy -0.2794 -0.1016) (xy -0.2794 0.9906) (xy 0.2794 0.9906)
			)
			(stroke
				(width 0)
				(type default)
			)
			(fill no)
			(layer "B.CrtYd")
		)
		(fp_line
			(start -0.2794 0.9906)
			(end -0.2794 -0.1016)
			(stroke
				(width 0.1)
				(type default)
			)
			(layer "B.Fab")
		)
		(fp_line
			(start 0.2794 0.9906)
			(end -0.2794 0.9906)
			(stroke
				(width 0.1)
				(type default)
			)
			(layer "B.Fab")
		)
		(fp_line
			(start -0.2794 -0.1016)
			(end 0.2794 -0.1016)
			(stroke
				(width 0.1)
				(type default)
			)
			(layer "B.Fab")
		)
		(fp_line
			(start 0.2794 -0.1016)
			(end 0.2794 0.9906)
			(stroke
				(width 0.1)
				(type default)
			)
			(layer "B.Fab")
		)
		(pad "1" smd rect
			(at 0 0 90)
			(size 0.508 0.508)
			(layers "B.Cu" "B.Mask" "B.Paste")
			(net "P0V7_GTL2014_VREF_6")
		)
		(pad "2" smd rect
			(at 0 0.889 90)
			(size 0.508 0.508)
			(layers "B.Cu" "B.Mask" "B.Paste")
			(net "GND")
		)
		(zone
			(layer "B.Cu")
			(hatch none 0.5)
			(connect_pads
				(clearance 0)
			)
			(min_thickness 0.25)
			(keepout
				(tracks not_allowed)
				(vias allowed)
				(pads allowed)
				(copperpour not_allowed)
				(footprints allowed)
			)
			(placement
				(enabled no)
				(sheetname "")
			)
			(fill
				(thermal_gap 0.5)
				(thermal_bridge_width 0.5)
				(island_removal_mode 0)
			)
			(polygon
				(pts
					(xy 449.5927 -149.1234) (xy 449.5927 -149.6314) (xy 449.9737 -149.6314) (xy 449.9737 -149.1234)
				)
			)
		)
		(zone
			(layer "B.Cu")
			(hatch none 0.5)
			(connect_pads
				(clearance 0)
			)
			(min_thickness 0.25)
			(keepout
				(tracks allowed)
				(vias not_allowed)
				(pads allowed)
				(copperpour not_allowed)
				(footprints allowed)
			)
			(placement
				(enabled no)
				(sheetname "")
			)
			(fill
				(thermal_gap 0.5)
				(thermal_bridge_width 0.5)
				(island_removal_mode 0)
			)
			(polygon
				(pts
					(xy 449.9737 -149.1234) (xy 449.9737 -149.6314) (xy 449.5927 -149.6314) (xy 449.5927 -149.1234)
				)
			)
		)
	)
)
